# SCM (Grand Teton) — schematic netlist excerpt (pin names and nets, part order shuffled) for the footprints in the layout excerpt that follows; sources: Cadence DE-HDL packaged netlist, KiCad conversion of 12092022_DA0F0TMDCD0_F0T_Management_Board_D_brd_V3_OCP.brd

C254  Q_CAP  0.1UF 25V 10% X7R  pkg 0402  page 41 : A = VCCIO1 ; B = GND
R701  Q_RES  0 5% CHIP  pkg 0402LF  page 28 : A = PWRGD_SYS_PWROK ; B = PWRGD_SYS_PWROK_R1

(kicad_pcb
	(version 20260206)
	(generator "pcbnew")
	(generator_version "10.0")
	(general
		(thickness 1.6)
		(legacy_teardrops no)
	)
	(paper "A4")
	(title_block
		(title "12092022_DA0F0TMDCD0_F0T_Management_Board_D_brd_V3_OCP.brd")
		(comment 1 "Grand Teton / footprints 1291-1292 of 1440")
	)
	(layers
		(0 "F.Cu" signal "TOP")
		(4 "In1.Cu" signal "GND")
		(6 "In2.Cu" signal "IN1")
		(8 "In3.Cu" signal "GND1")
		(10 "In4.Cu" signal "IN2")
		(12 "In5.Cu" signal "VCC")
		(14 "In6.Cu" signal "VCC1")
		(16 "In7.Cu" signal "IN3")
		(18 "In8.Cu" signal "GND2")
		(20 "In9.Cu" signal "IN4")
		(22 "In10.Cu" signal "GND3")
		(2 "B.Cu" signal "BOTTOM")
		(9 "F.Adhes" user "F.Adhesive")
		(11 "B.Adhes" user "B.Adhesive")
		(13 "F.Paste" user "Package Geometry/Pastemask Top")
		(15 "B.Paste" user "Package Geometry/Pastemask Bottom")
		(5 "F.SilkS" user "Ref Des/Silkscreen Top")
		(7 "B.SilkS" user "Ref Des/Silkscreen Bottom")
		(1 "F.Mask" user "Board Geometry/Soldermask Top")
		(3 "B.Mask" user "Board Geometry/Soldermask Bottom")
		(17 "Dwgs.User" user "User.Drawings")
		(19 "Cmts.User" user "User.Comments")
		(21 "Eco1.User" user "User.Eco1")
		(23 "Eco2.User" user "User.Eco2")
		(25 "Edge.Cuts" user "Board Geometry/Outline")
		(27 "Margin" user)
		(31 "F.CrtYd" user "Package Geometry/Place Bound Top")
		(29 "B.CrtYd" user "Package Geometry/Place Bound Bottom")
		(35 "F.Fab" user "Ref Des/Assembly Top")
		(33 "B.Fab" user "Ref Des/Assembly Bottom")
	)
	(footprint ""
		(layer "B.Cu")
		(at 51.3715 -86.0425 180)
		(property "Reference" "R701"
			(at 0 0 0)
			(layer "B.SilkS")
			(hide yes)
			(effects
				(font
					(size 1.27 1.27)
				)
				(justify mirror)
			)
		)
		(property "Value" ""
			(at 0 0 0)
			(layer "B.Fab")
			(effects
				(font
					(size 1.27 1.27)
				)
				(justify mirror)
			)
		)
		(duplicate_pad_numbers_are_jumpers no)
		(fp_line
			(start 0.7874 0.4064)
			(end 0.7874 -0.4064)
			(stroke
				(width 0.1524)
				(type default)
			)
			(layer "B.SilkS")
		)
		(fp_line
			(start 0.7874 -0.4064)
			(end -0.7874 -0.4064)
			(stroke
				(width 0.1524)
				(type default)
			)
			(layer "B.SilkS")
		)
		(fp_line
			(start -0.7874 0.4064)
			(end 0.7874 0.4064)
			(stroke
				(width 0.1524)
				(type default)
			)
			(layer "B.SilkS")
		)
		(fp_line
			(start -0.7874 -0.4064)
			(end -0.7874 0.4064)
			(stroke
				(width 0.1524)
				(type default)
			)
			(layer "B.SilkS")
		)
		(fp_line
			(start 0.67945 0.3048)
			(end 0.67945 -0.305054)
			(stroke
				(width 0.1)
				(type default)
			)
			(layer "B.Fab")
		)
		(fp_line
			(start 0.67945 -0.305054)
			(end 0.12065 -0.305054)
			(stroke
				(width 0.1)
				(type default)
			)
			(layer "B.Fab")
		)
		(fp_line
			(start 0.12065 0.3048)
			(end 0.67945 0.3048)
			(stroke
				(width 0.1)
				(type default)
			)
			(layer "B.Fab")
		)
		(fp_line
			(start 0.12065 0.2794)
			(end 0.12065 0.3048)
			(stroke
				(width 0.1)
				(type default)
			)
			(layer "B.Fab")
		)
		(fp_line
			(start 0.12065 -0.2794)
			(end -0.12065 -0.2794)
			(stroke
				(width 0.1)
				(type default)
			)
			(layer "B.Fab")
		)
		(fp_line
			(start 0.12065 -0.305054)
			(end 0.12065 -0.2794)
			(stroke
				(width 0.1)
				(type default)
			)
			(layer "B.Fab")
		)
		(fp_line
			(start -0.120396 0.3048)
			(end -0.120396 0.2794)
			(stroke
				(width 0.1)
				(type default)
			)
			(layer "B.Fab")
		)
		(fp_line
			(start -0.120396 0.2794)
			(end 0.12065 0.2794)
			(stroke
				(width 0.1)
				(type default)
			)
			(layer "B.Fab")
		)
		(fp_line
			(start -0.12065 -0.2794)
			(end -0.12065 -0.3048)
			(stroke
				(width 0.1)
				(type default)
			)
			(layer "B.Fab")
		)
		(fp_line
			(start -0.12065 -0.3048)
			(end -0.67945 -0.3048)
			(stroke
				(width 0.1)
				(type default)
			)
			(layer "B.Fab")
		)
		(fp_line
			(start -0.67945 0.3048)
			(end -0.120396 0.3048)
			(stroke
				(width 0.1)
				(type default)
			)
			(layer "B.Fab")
		)
		(fp_line
			(start -0.67945 -0.3048)
			(end -0.67945 0.3048)
			(stroke
				(width 0.1)
				(type default)
			)
			(layer "B.Fab")
		)
		(pad "1" smd circle
			(at 0.40005 0)
			(size 0 0)
			(layers "B.Cu" "B.Mask" "B.Paste")
			(net "PWRGD_SYS_PWROK")
		)
		(pad "2" smd circle
			(at -0.40005 0)
			(size 0 0)
			(layers "B.Cu" "B.Mask" "B.Paste")
			(net "PWRGD_SYS_PWROK_R1")
		)
	)
	(footprint ""
		(layer "B.Cu")
		(at 17.864328 -96.782128 -90)
		(property "Reference" "C254"
			(at 0 0 90)
			(layer "B.SilkS")
			(hide yes)
			(effects
				(font
					(size 1.27 1.27)
				)
				(justify mirror)
			)
		)
		(property "Value" ""
			(at 0 0 90)
			(layer "B.Fab")
			(effects
				(font
					(size 1.27 1.27)
				)
				(justify mirror)
			)
		)
		(duplicate_pad_numbers_are_jumpers no)
		(fp_line
			(start -0.69215 0.2921)
			(end 0.69215 0.2921)
			(stroke
				(width 0.1524)
				(type default)
			)
			(layer "B.SilkS")
		)
		(fp_line
			(start 0.69215 0.2921)
			(end 0.69215 -0.2921)
			(stroke
				(width 0.1524)
				(type default)
			)
			(layer "B.SilkS")
		)
		(fp_line
			(start -0.69215 -0.2921)
			(end -0.69215 0.2921)
			(stroke
				(width 0.1524)
				(type default)
			)
			(layer "B.SilkS")
		)
		(fp_line
			(start 0.69215 -0.2921)
			(end -0.69215 -0.2921)
			(stroke
				(width 0.1524)
				(type default)
			)
			(layer "B.SilkS")
		)
		(fp_line
			(start -0.51435 0.2794)
			(end 0.51435 0.2794)
			(stroke
				(width 0.1)
				(type default)
			)
			(layer "B.Fab")
		)
		(fp_line
			(start 0.51435 0.2794)
			(end 0.51435 -0.2794)
			(stroke
				(width 0.1)
				(type default)
			)
			(layer "B.Fab")
		)
		(fp_line
			(start -0.51435 -0.2794)
			(end -0.51435 0.2794)
			(stroke
				(width 0.1)
				(type default)
			)
			(layer "B.Fab")
		)
		(fp_line
			(start 0.51435 -0.2794)
			(end -0.51435 -0.2794)
			(stroke
				(width 0.1)
				(type default)
			)
			(layer "B.Fab")
		)
		(pad "1" smd circle
			(at 0.40005 0 90)
			(size 0 0)
			(layers "B.Cu" "B.Mask" "B.Paste")
			(net "VCCIO1")
		)
		(pad "2" smd circle
			(at -0.40005 0 90)
			(size 0 0)
			(layers "B.Cu" "B.Mask" "B.Paste")
			(net "GND")
		)
		(zone
			(layer "B.Cu")
			(hatch none 0.5)
			(connect_pads
				(clearance 0)
			)
			(min_thickness 0.25)
			(keepout
				(tracks not_allowed)
				(vias allowed)
				(pads allowed)
				(copperpour not_allowed)
				(footprints allowed)
			)
			(placement
				(enabled no)
				(sheetname "")
			)
			(fill
				(thermal_gap 0.5)
				(thermal_bridge_width 0.5)
				(island_removal_mode 0)
			)
			(polygon
				(pts
					(xy 17.776698 -96.591628) (xy 17.718532 -96.683068) (xy 17.718532 -96.882458) (xy 17.776698 -96.972628)
					(xy 17.951958 -96.972628) (xy 18.010378 -96.882458) (xy 18.010378 -96.683068) (xy 17.952212 -96.591628)
				)
			)
		)
	)
)
